%FSTAX25Y25*%
%MOIN*%
%SFA1B1*%

%IPPOS*%
%ADD9514C,0.039370*%
%LNgrandmaster-slotholes-1*%
%LPD*%
G54D9514*
X1192496Y0898126D02*
Y0890252D01*
X1215921Y0882378D02*
X1206079D01*
X1214937Y0906D02*
X1207063D01*
M02*